(kicad_pcb
	(version 20260206)
	(generator "pcbnew")
	(generator_version "10.0")
	(general
		(thickness 1.6)
		(legacy_teardrops no)
	)
	(paper "A4")
	(title_block
		(title "v1-chassis-manager — T6M_CM_d_v01_1031_1645.brd")
		(comment 1 "Open CloudServer (Microsoft) / footprints 2133-2142 of 2512")
	)
	(layers
		(0 "F.Cu" signal "TOP")
		(4 "In1.Cu" signal "GND1")
		(6 "In2.Cu" signal "IN1")
		(8 "In3.Cu" signal "VCC1")
		(10 "In4.Cu" signal "VCC2")
		(12 "In5.Cu" signal "GND2")
		(14 "In6.Cu" signal "IN2")
		(16 "In7.Cu" signal "IN3")
		(18 "In8.Cu" signal "GND3")
		(2 "B.Cu" signal "BOTTOM")
		(9 "F.Adhes" user "F.Adhesive")
		(11 "B.Adhes" user "B.Adhesive")
		(13 "F.Paste" user "Package Geometry/Pastemask Top")
		(15 "B.Paste" user "Package Geometry/Pastemask Bottom")
		(5 "F.SilkS" user "Ref Des/Silkscreen Top")
		(7 "B.SilkS" user "Ref Des/Silkscreen Bottom")
		(1 "F.Mask" user "Board Geometry/Soldermask Top")
		(3 "B.Mask" user "Board Geometry/Soldermask Bottom")
		(17 "Dwgs.User" user "User.Drawings")
		(19 "Cmts.User" user "User.Comments")
		(21 "Eco1.User" user "User.Eco1")
		(23 "Eco2.User" user "User.Eco2")
		(25 "Edge.Cuts" user "Board Geometry/Outline")
		(27 "Margin" user)
		(31 "F.CrtYd" user "Package Geometry/Place Bound Top")
		(29 "B.CrtYd" user "Package Geometry/Place Bound Bottom")
		(35 "F.Fab" user "Ref Des/Assembly Top")
		(33 "B.Fab" user "Ref Des/Assembly Bottom")
	)
	(footprint ""
		(layer "B.Cu")
		(at 147.305014 -71.651622)
		(property "Reference" "C349"
			(at 4.93522 -0.616458 0)
			(unlocked yes)
			(layer "B.SilkS")
			(effects
				(font
					(size 0.7874 0.5842)
					(thickness 0.1524)
				)
				(justify left mirror)
			)
		)
		(property "Value" ""
			(at 0 0 0)
			(layer "B.Fab")
			(effects
				(font
					(size 1.27 1.27)
				)
				(justify mirror)
			)
		)
		(duplicate_pad_numbers_are_jumpers no)
		(fp_line
			(start -0.7874 -0.4064)
			(end -0.7874 0.4064)
			(stroke
				(width 0.1524)
				(type default)
			)
			(layer "B.SilkS")
		)
		(fp_line
			(start -0.7874 0.4064)
			(end 0.7874 0.4064)
			(stroke
				(width 0.1524)
				(type default)
			)
			(layer "B.SilkS")
		)
		(fp_line
			(start 0 0.381)
			(end 0 -0.381)
			(stroke
				(width 0.1524)
				(type default)
			)
			(layer "B.SilkS")
		)
		(fp_line
			(start 0.7874 -0.4064)
			(end -0.7874 -0.4064)
			(stroke
				(width 0.1524)
				(type default)
			)
			(layer "B.SilkS")
		)
		(fp_line
			(start 0.7874 0.4064)
			(end 0.7874 -0.4064)
			(stroke
				(width 0.1524)
				(type default)
			)
			(layer "B.SilkS")
		)
		(fp_poly
			(pts
				(xy 0.5334 0.254) (xy 0.635 0.254) (xy 0.635 0.2286) (xy 0.635 -0.254) (xy 0.5334 -0.254) (xy 0.5334 -0.2794)
				(xy -0.5334 -0.2794) (xy -0.5334 -0.254) (xy -0.635 -0.254) (xy -0.635 0.254) (xy -0.5334 0.254)
				(xy -0.5334 0.2794) (xy 0.508 0.2794) (xy 0.5334 0.2794)
			)
			(stroke
				(width 0)
				(type default)
			)
			(fill no)
			(layer "B.CrtYd")
		)
		(pad "1" smd rect
			(at -0.40005 0 180)
			(size 0.4572 0.508)
			(layers "B.Cu" "B.Mask" "B.Paste")
			(net "GND")
		)
		(pad "2" smd rect
			(at 0.40005 0 180)
			(size 0.4572 0.508)
			(layers "B.Cu" "B.Mask" "B.Paste")
			(net "P1V8_SATA_AVDD_NODE1")
		)
	)
	(footprint ""
		(layer "B.Cu")
		(at 144.51076 -187.999624 90)
		(property "Reference" "R969"
			(at 4.438396 -1.775206 270)
			(unlocked yes)
			(layer "B.SilkS")
			(effects
				(font
					(size 0.7874 0.5842)
					(thickness 0.1524)
				)
				(justify left mirror)
			)
		)
		(property "Value" ""
			(at 0 0 90)
			(layer "B.Fab")
			(effects
				(font
					(size 1.27 1.27)
				)
				(justify mirror)
			)
		)
		(duplicate_pad_numbers_are_jumpers no)
		(fp_line
			(start 0.7874 -0.4064)
			(end -0.7874 -0.4064)
			(stroke
				(width 0.1524)
				(type default)
			)
			(layer "B.SilkS")
		)
		(fp_line
			(start -0.7874 -0.4064)
			(end -0.7874 0.4064)
			(stroke
				(width 0.1524)
				(type default)
			)
			(layer "B.SilkS")
		)
		(fp_line
			(start 0.7874 0.4064)
			(end 0.7874 -0.4064)
			(stroke
				(width 0.1524)
				(type default)
			)
			(layer "B.SilkS")
		)
		(fp_line
			(start -0.7874 0.4064)
			(end 0.7874 0.4064)
			(stroke
				(width 0.1524)
				(type default)
			)
			(layer "B.SilkS")
		)
		(fp_poly
			(pts
				(xy 0.508 0.2794) (xy 0.508 0.2286) (xy 0.635 0.2286) (xy 0.635 -0.254) (xy 0.5334 -0.254) (xy 0.5334 -0.2794)
				(xy -0.5334 -0.2794) (xy -0.5334 -0.254) (xy -0.635 -0.254) (xy -0.635 0.254) (xy -0.5334 0.254)
				(xy -0.5334 0.2794)
			)
			(stroke
				(width 0)
				(type default)
			)
			(fill no)
			(layer "B.CrtYd")
		)
		(pad "1" smd rect
			(at -0.40005 0 270)
			(size 0.4572 0.508)
			(layers "B.Cu" "B.Mask" "B.Paste")
			(net "UART_T11_NODE3_RXD")
		)
		(pad "2" smd rect
			(at 0.40005 0 270)
			(size 0.4572 0.508)
			(layers "B.Cu" "B.Mask" "B.Paste")
			(net "UART_T11_NODE3_RXD_R")
		)
	)
	(footprint ""
		(layer "B.Cu")
		(at 91.47302 -74.756518)
		(property "Reference" "R159"
			(at 4.07797 0.606044 0)
			(unlocked yes)
			(layer "B.SilkS")
			(effects
				(font
					(size 0.7874 0.5842)
					(thickness 0.1524)
				)
				(justify left mirror)
			)
		)
		(property "Value" ""
			(at 0 0 0)
			(layer "B.Fab")
			(effects
				(font
					(size 1.27 1.27)
				)
				(justify mirror)
			)
		)
		(duplicate_pad_numbers_are_jumpers no)
		(fp_line
			(start -0.7874 -0.4064)
			(end -0.7874 0.4064)
			(stroke
				(width 0.1524)
				(type default)
			)
			(layer "B.SilkS")
		)
		(fp_line
			(start -0.7874 0.4064)
			(end 0.7874 0.4064)
			(stroke
				(width 0.1524)
				(type default)
			)
			(layer "B.SilkS")
		)
		(fp_line
			(start 0.7874 -0.4064)
			(end -0.7874 -0.4064)
			(stroke
				(width 0.1524)
				(type default)
			)
			(layer "B.SilkS")
		)
		(fp_line
			(start 0.7874 0.4064)
			(end 0.7874 -0.4064)
			(stroke
				(width 0.1524)
				(type default)
			)
			(layer "B.SilkS")
		)
		(fp_poly
			(pts
				(xy 0.508 0.2794) (xy 0.508 0.2286) (xy 0.635 0.2286) (xy 0.635 -0.254) (xy 0.5334 -0.254) (xy 0.5334 -0.2794)
				(xy -0.5334 -0.2794) (xy -0.5334 -0.254) (xy -0.635 -0.254) (xy -0.635 0.254) (xy -0.5334 0.254)
				(xy -0.5334 0.2794)
			)
			(stroke
				(width 0)
				(type default)
			)
			(fill no)
			(layer "B.CrtYd")
		)
		(pad "1" smd rect
			(at -0.40005 0 180)
			(size 0.4572 0.508)
			(layers "B.Cu" "B.Mask" "B.Paste")
			(net "PD_CPU_NODE1_HVMGEAR_SEL")
		)
		(pad "2" smd rect
			(at 0.40005 0 180)
			(size 0.4572 0.508)
			(layers "B.Cu" "B.Mask" "B.Paste")
			(net "P1V05_SUS_NODE1")
		)
	)
	(footprint ""
		(layer "B.Cu")
		(at 108.5342 -137.415778)
		(property "Reference" "PR41"
			(at 1.000252 1.800606 0)
			(unlocked yes)
			(layer "B.SilkS")
			(effects
				(font
					(size 0.7874 0.5842)
					(thickness 0.1524)
				)
				(justify mirror)
			)
		)
		(property "Value" ""
			(at 0 0 0)
			(layer "B.Fab")
			(effects
				(font
					(size 1.27 1.27)
				)
				(justify mirror)
			)
		)
		(duplicate_pad_numbers_are_jumpers no)
		(fp_line
			(start -1.2954 -0.5842)
			(end -1.2954 0.5842)
			(stroke
				(width 0.1524)
				(type default)
			)
			(layer "B.SilkS")
		)
		(fp_line
			(start -1.2954 0.5842)
			(end 1.2954 0.5842)
			(stroke
				(width 0.1524)
				(type default)
			)
			(layer "B.SilkS")
		)
		(fp_line
			(start 1.2954 -0.5842)
			(end -1.2954 -0.5842)
			(stroke
				(width 0.1524)
				(type default)
			)
			(layer "B.SilkS")
		)
		(fp_line
			(start 1.2954 0.5842)
			(end 1.2954 -0.5842)
			(stroke
				(width 0.1524)
				(type default)
			)
			(layer "B.SilkS")
		)
		(fp_poly
			(pts
				(xy -1.143 -0.3556) (xy -1.143 0.3556) (xy -0.8636 0.3556) (xy -0.8636 0.4572) (xy 0.8636 0.4572)
				(xy 0.8636 0.4318) (xy 0.8636 0.3556) (xy 1.143 0.3556) (xy 1.143 -0.3556) (xy 0.8636 -0.3556) (xy 0.8636 -0.4572)
				(xy -0.8636 -0.4572) (xy -0.8636 -0.3556)
			)
			(stroke
				(width 0)
				(type default)
			)
			(fill no)
			(layer "B.CrtYd")
		)
		(pad "1" smd rect
			(at -0.7366 0 90)
			(size 0.7112 0.8128)
			(layers "B.Cu" "B.Mask" "B.Paste")
			(net "P5V_STB_NODE1")
		)
		(pad "2" smd rect
			(at 0.7366 0 90)
			(size 0.7112 0.8128)
			(layers "B.Cu" "B.Mask" "B.Paste")
			(net "VR_PVCCP_NODE1_VCC")
		)
	)
	(footprint ""
		(layer "B.Cu")
		(at 77.396086 -125.438662)
		(property "Reference" "C285"
			(at 3.903472 0.243078 0)
			(unlocked yes)
			(layer "B.SilkS")
			(effects
				(font
					(size 0.7874 0.5842)
					(thickness 0.1524)
				)
				(justify left mirror)
			)
		)
		(property "Value" ""
			(at 0 0 0)
			(layer "B.Fab")
			(effects
				(font
					(size 1.27 1.27)
				)
				(justify mirror)
			)
		)
		(duplicate_pad_numbers_are_jumpers no)
		(fp_line
			(start -0.7874 -0.4064)
			(end -0.7874 0.4064)
			(stroke
				(width 0.1524)
				(type default)
			)
			(layer "B.SilkS")
		)
		(fp_line
			(start -0.7874 0.4064)
			(end 0.7874 0.4064)
			(stroke
				(width 0.1524)
				(type default)
			)
			(layer "B.SilkS")
		)
		(fp_line
			(start 0 0.381)
			(end 0 -0.381)
			(stroke
				(width 0.1524)
				(type default)
			)
			(layer "B.SilkS")
		)
		(fp_line
			(start 0.7874 -0.4064)
			(end -0.7874 -0.4064)
			(stroke
				(width 0.1524)
				(type default)
			)
			(layer "B.SilkS")
		)
		(fp_line
			(start 0.7874 0.4064)
			(end 0.7874 -0.4064)
			(stroke
				(width 0.1524)
				(type default)
			)
			(layer "B.SilkS")
		)
		(fp_poly
			(pts
				(xy 0.5334 0.254) (xy 0.635 0.254) (xy 0.635 0.2286) (xy 0.635 -0.254) (xy 0.5334 -0.254) (xy 0.5334 -0.2794)
				(xy -0.5334 -0.2794) (xy -0.5334 -0.254) (xy -0.635 -0.254) (xy -0.635 0.254) (xy -0.5334 0.254)
				(xy -0.5334 0.2794) (xy 0.508 0.2794) (xy 0.5334 0.2794)
			)
			(stroke
				(width 0)
				(type default)
			)
			(fill no)
			(layer "B.CrtYd")
		)
		(pad "1" smd rect
			(at -0.40005 0 180)
			(size 0.4572 0.508)
			(layers "B.Cu" "B.Mask" "B.Paste")
			(net "BMC_NODE1_VCC_1V8_PCIEA")
		)
		(pad "2" smd rect
			(at 0.40005 0 180)
			(size 0.4572 0.508)
			(layers "B.Cu" "B.Mask" "B.Paste")
			(net "GND")
		)
	)
	(footprint ""
		(layer "B.Cu")
		(at 144.51076 -184.951624 -90)
		(property "Reference" "C732"
			(at -4.357624 2.41427 270)
			(unlocked yes)
			(layer "B.SilkS")
			(effects
				(font
					(size 0.7874 0.5842)
					(thickness 0.1524)
				)
				(justify left mirror)
			)
		)
		(property "Value" ""
			(at 0 0 90)
			(layer "B.Fab")
			(effects
				(font
					(size 1.27 1.27)
				)
				(justify mirror)
			)
		)
		(duplicate_pad_numbers_are_jumpers no)
		(fp_line
			(start -0.7874 0.4064)
			(end 0.7874 0.4064)
			(stroke
				(width 0.1524)
				(type default)
			)
			(layer "B.SilkS")
		)
		(fp_line
			(start 0.7874 0.4064)
			(end 0.7874 -0.4064)
			(stroke
				(width 0.1524)
				(type default)
			)
			(layer "B.SilkS")
		)
		(fp_line
			(start 0 0.381)
			(end 0 -0.381)
			(stroke
				(width 0.1524)
				(type default)
			)
			(layer "B.SilkS")
		)
		(fp_line
			(start -0.7874 -0.4064)
			(end -0.7874 0.4064)
			(stroke
				(width 0.1524)
				(type default)
			)
			(layer "B.SilkS")
		)
		(fp_line
			(start 0.7874 -0.4064)
			(end -0.7874 -0.4064)
			(stroke
				(width 0.1524)
				(type default)
			)
			(layer "B.SilkS")
		)
		(fp_poly
			(pts
				(xy 0.5334 0.254) (xy 0.635 0.254) (xy 0.635 0.2286) (xy 0.635 -0.254) (xy 0.5334 -0.254) (xy 0.5334 -0.2794)
				(xy -0.5334 -0.2794) (xy -0.5334 -0.254) (xy -0.635 -0.254) (xy -0.635 0.254) (xy -0.5334 0.254)
				(xy -0.5334 0.2794) (xy 0.508 0.2794) (xy 0.5334 0.2794)
			)
			(stroke
				(width 0)
				(type default)
			)
			(fill no)
			(layer "B.CrtYd")
		)
		(pad "1" smd rect
			(at -0.40005 0 90)
			(size 0.4572 0.508)
			(layers "B.Cu" "B.Mask" "B.Paste")
			(net "UART_T11_NODE3_RXD")
		)
		(pad "2" smd rect
			(at 0.40005 0 90)
			(size 0.4572 0.508)
			(layers "B.Cu" "B.Mask" "B.Paste")
			(net "GND")
		)
	)
	(footprint ""
		(layer "B.Cu")
		(at 139.252452 -139.57935 -90)
		(property "Reference" "C867"
			(at -0.451866 0.585216 0)
			(unlocked yes)
			(layer "B.SilkS")
			(effects
				(font
					(size 0.7874 0.5842)
					(thickness 0.1524)
				)
				(justify left mirror)
			)
		)
		(property "Value" ""
			(at 0 0 90)
			(layer "B.Fab")
			(effects
				(font
					(size 1.27 1.27)
				)
				(justify mirror)
			)
		)
		(duplicate_pad_numbers_are_jumpers no)
		(fp_line
			(start -0.7874 0.4064)
			(end 0.7874 0.4064)
			(stroke
				(width 0.1524)
				(type default)
			)
			(layer "B.SilkS")
		)
		(fp_line
			(start 0.7874 0.4064)
			(end 0.7874 -0.4064)
			(stroke
				(width 0.1524)
				(type default)
			)
			(layer "B.SilkS")
		)
		(fp_line
			(start 0 0.381)
			(end 0 -0.381)
			(stroke
				(width 0.1524)
				(type default)
			)
			(layer "B.SilkS")
		)
		(fp_line
			(start -0.7874 -0.4064)
			(end -0.7874 0.4064)
			(stroke
				(width 0.1524)
				(type default)
			)
			(layer "B.SilkS")
		)
		(fp_line
			(start 0.7874 -0.4064)
			(end -0.7874 -0.4064)
			(stroke
				(width 0.1524)
				(type default)
			)
			(layer "B.SilkS")
		)
		(fp_poly
			(pts
				(xy 0.5334 0.254) (xy 0.635 0.254) (xy 0.635 0.2286) (xy 0.635 -0.254) (xy 0.5334 -0.254) (xy 0.5334 -0.2794)
				(xy -0.5334 -0.2794) (xy -0.5334 -0.254) (xy -0.635 -0.254) (xy -0.635 0.254) (xy -0.5334 0.254)
				(xy -0.5334 0.2794) (xy 0.508 0.2794) (xy 0.5334 0.2794)
			)
			(stroke
				(width 0)
				(type default)
			)
			(fill no)
			(layer "B.CrtYd")
		)
		(pad "1" smd rect
			(at -0.40005 0 90)
			(size 0.4572 0.508)
			(layers "B.Cu" "B.Mask" "B.Paste")
			(net "P3V3_NODE1")
		)
		(pad "2" smd rect
			(at 0.40005 0 90)
			(size 0.4572 0.508)
			(layers "B.Cu" "B.Mask" "B.Paste")
			(net "GND")
		)
	)
	(footprint ""
		(layer "B.Cu")
		(at 141.08176 -187.948824 -90)
		(property "Reference" "C741"
			(at -4.544568 1.490472 270)
			(unlocked yes)
			(layer "B.SilkS")
			(effects
				(font
					(size 0.7874 0.5842)
					(thickness 0.1524)
				)
				(justify left mirror)
			)
		)
		(property "Value" ""
			(at 0 0 90)
			(layer "B.Fab")
			(effects
				(font
					(size 1.27 1.27)
				)
				(justify mirror)
			)
		)
		(duplicate_pad_numbers_are_jumpers no)
		(fp_line
			(start -0.7874 0.4064)
			(end 0.7874 0.4064)
			(stroke
				(width 0.1524)
				(type default)
			)
			(layer "B.SilkS")
		)
		(fp_line
			(start 0.7874 0.4064)
			(end 0.7874 -0.4064)
			(stroke
				(width 0.1524)
				(type default)
			)
			(layer "B.SilkS")
		)
		(fp_line
			(start 0 0.381)
			(end 0 -0.381)
			(stroke
				(width 0.1524)
				(type default)
			)
			(layer "B.SilkS")
		)
		(fp_line
			(start -0.7874 -0.4064)
			(end -0.7874 0.4064)
			(stroke
				(width 0.1524)
				(type default)
			)
			(layer "B.SilkS")
		)
		(fp_line
			(start 0.7874 -0.4064)
			(end -0.7874 -0.4064)
			(stroke
				(width 0.1524)
				(type default)
			)
			(layer "B.SilkS")
		)
		(fp_poly
			(pts
				(xy 0.5334 0.254) (xy 0.635 0.254) (xy 0.635 0.2286) (xy 0.635 -0.254) (xy 0.5334 -0.254) (xy 0.5334 -0.2794)
				(xy -0.5334 -0.2794) (xy -0.5334 -0.254) (xy -0.635 -0.254) (xy -0.635 0.254) (xy -0.5334 0.254)
				(xy -0.5334 0.2794) (xy 0.508 0.2794) (xy 0.5334 0.2794)
			)
			(stroke
				(width 0)
				(type default)
			)
			(fill no)
			(layer "B.CrtYd")
		)
		(pad "1" smd rect
			(at -0.40005 0 90)
			(size 0.4572 0.508)
			(layers "B.Cu" "B.Mask" "B.Paste")
			(net "UART_T11_NODE4_TXD_R")
		)
		(pad "2" smd rect
			(at 0.40005 0 90)
			(size 0.4572 0.508)
			(layers "B.Cu" "B.Mask" "B.Paste")
			(net "GND")
		)
	)
	(footprint ""
		(layer "B.Cu")
		(at 56.519572 -70.354698)
		(property "Reference" "C80"
			(at -13.618972 31.441136 0)
			(unlocked yes)
			(layer "B.SilkS")
			(effects
				(font
					(size 0.7874 0.5842)
					(thickness 0.1524)
				)
				(justify left mirror)
			)
		)
		(property "Value" ""
			(at 0 0 0)
			(layer "B.Fab")
			(effects
				(font
					(size 1.27 1.27)
				)
				(justify mirror)
			)
		)
		(duplicate_pad_numbers_are_jumpers no)
		(fp_line
			(start -0.7874 -0.4064)
			(end -0.7874 0.4064)
			(stroke
				(width 0.1524)
				(type default)
			)
			(layer "B.SilkS")
		)
		(fp_line
			(start -0.7874 0.4064)
			(end 0.7874 0.4064)
			(stroke
				(width 0.1524)
				(type default)
			)
			(layer "B.SilkS")
		)
		(fp_line
			(start 0 0.381)
			(end 0 -0.381)
			(stroke
				(width 0.1524)
				(type default)
			)
			(layer "B.SilkS")
		)
		(fp_line
			(start 0.7874 -0.4064)
			(end -0.7874 -0.4064)
			(stroke
				(width 0.1524)
				(type default)
			)
			(layer "B.SilkS")
		)
		(fp_line
			(start 0.7874 0.4064)
			(end 0.7874 -0.4064)
			(stroke
				(width 0.1524)
				(type default)
			)
			(layer "B.SilkS")
		)
		(fp_poly
			(pts
				(xy 0.5334 0.254) (xy 0.635 0.254) (xy 0.635 0.2286) (xy 0.635 -0.254) (xy 0.5334 -0.254) (xy 0.5334 -0.2794)
				(xy -0.5334 -0.2794) (xy -0.5334 -0.254) (xy -0.635 -0.254) (xy -0.635 0.254) (xy -0.5334 0.254)
				(xy -0.5334 0.2794) (xy 0.508 0.2794) (xy 0.5334 0.2794)
			)
			(stroke
				(width 0)
				(type default)
			)
			(fill no)
			(layer "B.CrtYd")
		)
		(pad "1" smd rect
			(at -0.40005 0 180)
			(size 0.4572 0.508)
			(layers "B.Cu" "B.Mask" "B.Paste")
			(net "P1V05_VCCACLK_DDR3_NODE1")
		)
		(pad "2" smd rect
			(at 0.40005 0 180)
			(size 0.4572 0.508)
			(layers "B.Cu" "B.Mask" "B.Paste")
			(net "GND")
		)
	)
	(footprint ""
		(layer "B.Cu")
		(at 141.005052 -144.76095 -90)
		(property "Reference" "C866"
			(at -0.031242 1.143762 0)
			(unlocked yes)
			(layer "B.SilkS")
			(effects
				(font
					(size 0.7874 0.5842)
					(thickness 0.1524)
				)
				(justify left mirror)
			)
		)
		(property "Value" ""
			(at 0 0 90)
			(layer "B.Fab")
			(effects
				(font
					(size 1.27 1.27)
				)
				(justify mirror)
			)
		)
		(duplicate_pad_numbers_are_jumpers no)
		(fp_line
			(start -0.7874 0.4064)
			(end 0.7874 0.4064)
			(stroke
				(width 0.1524)
				(type default)
			)
			(layer "B.SilkS")
		)
		(fp_line
			(start 0.7874 0.4064)
			(end 0.7874 -0.4064)
			(stroke
				(width 0.1524)
				(type default)
			)
			(layer "B.SilkS")
		)
		(fp_line
			(start 0 0.381)
			(end 0 -0.381)
			(stroke
				(width 0.1524)
				(type default)
			)
			(layer "B.SilkS")
		)
		(fp_line
			(start -0.7874 -0.4064)
			(end -0.7874 0.4064)
			(stroke
				(width 0.1524)
				(type default)
			)
			(layer "B.SilkS")
		)
		(fp_line
			(start 0.7874 -0.4064)
			(end -0.7874 -0.4064)
			(stroke
				(width 0.1524)
				(type default)
			)
			(layer "B.SilkS")
		)
		(fp_poly
			(pts
				(xy 0.5334 0.254) (xy 0.635 0.254) (xy 0.635 0.2286) (xy 0.635 -0.254) (xy 0.5334 -0.254) (xy 0.5334 -0.2794)
				(xy -0.5334 -0.2794) (xy -0.5334 -0.254) (xy -0.635 -0.254) (xy -0.635 0.254) (xy -0.5334 0.254)
				(xy -0.5334 0.2794) (xy 0.508 0.2794) (xy 0.5334 0.2794)
			)
			(stroke
				(width 0)
				(type default)
			)
			(fill no)
			(layer "B.CrtYd")
		)
		(pad "1" smd rect
			(at -0.40005 0 90)
			(size 0.4572 0.508)
			(layers "B.Cu" "B.Mask" "B.Paste")
			(net "P3V3_NODE1")
		)
		(pad "2" smd rect
			(at 0.40005 0 90)
			(size 0.4572 0.508)
			(layers "B.Cu" "B.Mask" "B.Paste")
			(net "GND")
		)
	)
)
